#ISCELL
  mstr_misc dns *
  *
#ISCELL
  pure_quanta quanta_title_block_c *
  *
#ISCELL
  standard offpage *
  page161_i1
#CELL
  pure_quanta q_res *
  page161_i10
#ISCELL
  pure_quanta_power gnd *
  page161_i11
#CELL
  pure_quanta q_res *
  page161_i12
#CELL
  pure_quanta q_cap *
  page161_i13
#ISCELL
  pure_quanta_power universal_gnd *
  page161_i14
#ISCELL
  standard offpage *
  page161_i15
#ISCELL
  standard offpage *
  page161_i16
#ISCELL
  pure_quanta_power universal_gnd *
  page161_i17
#ISCELL
  pure_quanta_power gnd *
  page161_i18
#CELL
  pure_quanta q_res *
  page161_i19
#ISCELL
  pure_quanta_power universal_gnd *
  page161_i2
#ISCELL
  pure_quanta_power universal_gnd *
  page161_i20
#ISCELL
  pure_quanta_power universal_gnd *
  page161_i21
#CELL
  pure_quanta q_res *
  page161_i22
#ISCELL
  standard offpage *
  page161_i23
#CELL
  pure_quanta q_res *
  page161_i24
#ISCELL
  standard offpage *
  page161_i25
#ISCELL
  standard offpage *
  page161_i26
#CELL
  pure_quanta q_cap *
  page161_i27
#CELL
  pure_quanta conn3_210hp1030br1 *
  page161_i28
#ISCELL
  pure_quanta_power universal_gnd *
  page161_i29
#ISCELL
  pure_quanta_power gnd *
  page161_i3
#CELL
  pure_quanta q_cap *
  page161_i30
#ISCELL
  standard offpage *
  page161_i31
#ISCELL
  standard offpage *
  page161_i32
#ISCELL
  pure_quanta_power gnd *
  page161_i33
#CELL
  pure_quanta q_res *
  page161_i34
#ISCELL
  pure_quanta_power universal_power *
  page161_i35
#CELL
  pure_quanta q_res *
  page161_i36
#CELL
  pure_quanta q_res *
  page161_i37
#ISCELL
  pure_quanta_power universal_gnd *
  page161_i38
#CELL
  pure_quanta q_res *
  page161_i39
#CELL
  pure_quanta q_cap *
  page161_i4
#ISCELL
  standard offpage *
  page161_i40
#ISCELL
  pure_quanta_power universal_power *
  page161_i41
#ISCELL
  pure_quanta_power gnd *
  page161_i42
#CELL
  pure_quanta zener_ac *
  page161_i43
#CELL
  pure_quanta q_fuse *
  page161_i44
#ISCELL
  pure_quanta_power universal_power *
  page161_i45
#CELL
  pure_quanta q_cap *
  page161_i46
#CELL
  pure_quanta q_res *
  page161_i47
#CELL
  pure_quanta q_res *
  page161_i48
#ISCELL
  pure_quanta_power universal_gnd *
  page161_i49
#CELL
  pure_quanta q_res *
  page161_i5
#CELL
  pure_quanta q_cap *
  page161_i50
#CELL
  pure_quanta q_res *
  page161_i51
#CELL
  pure_quanta q_res *
  page161_i52
#CELL
  pure_quanta q_res *
  page161_i53
#CELL
  pure_quanta q_res *
  page161_i54
#ISCELL
  pure_quanta_power universal_power *
  page161_i55
#CELL
  pure_quanta q_res *
  page161_i56
#ISCELL
  pure_quanta_power universal_gnd *
  page161_i57
#CELL
  pure_quanta mp5990gma1111z *
  page161_i58
#CELL
  pure_quanta q_cap *
  page161_i59
#CELL
  pure_quanta q_res *
  page161_i6
#ISCELL
  standard offpage *
  page161_i60
#ISCELL
  standard offpage *
  page161_i61
#ISCELL
  standard offpage *
  page161_i62
#CELL
  pure_quanta q_res *
  page161_i63
#ISCELL
  pure_quanta_power universal_power *
  page161_i64
#CELL
  pure_quanta q_res *
  page161_i65
#ISCELL
  pure_quanta_power universal_gnd *
  page161_i66
#ISCELL
  standard offpage *
  page161_i67
#ISCELL
  standard offpage *
  page161_i68
#ISCELL
  pure_quanta_power universal_gnd *
  page161_i69
#ISCELL
  pure_quanta_power gnd *
  page161_i7
#CELL
  pure_quanta q_res *
  page161_i70
#CELL
  pure_quanta q_res *
  page161_i71
#CELL
  pure_quanta q_cap *
  page161_i72
#ISCELL
  standard offpage *
  page161_i73
#ISCELL
  pure_quanta_power universal_gnd *
  page161_i74
#CELL
  pure_quanta q_cap *
  page161_i75
#ISCELL
  standard offpage *
  page161_i76
#ISCELL
  pure_quanta_power universal_gnd *
  page161_i77
#CELL
  pure_quanta q_cap *
  page161_i78
#CELL
  pure_quanta q_res *
  page161_i79
#CELL
  pure_quanta conn3_210hp1030br1 *
  page161_i8
#CELL
  pure_quanta q_res *
  page161_i80
#CELL
  pure_quanta q_res *
  page161_i81
#ISCELL
  standard offpage *
  page161_i82
#ISCELL
  pure_quanta_power universal_gnd *
  page161_i83
#CELL
  pure_quanta q_cap *
  page161_i84
#CELL
  pure_quanta q_res *
  page161_i85
#CELL
  pure_quanta q_res *
  page161_i86
#ISCELL
  pure_quanta_power universal_gnd *
  page161_i87
#ISCELL
  pure_quanta_power gnd *
  page161_i88
#CELL
  pure_quanta ss15p3sm386a *
  page161_i89
#CELL
  pure_quanta mosfet_nch_gds_esd_protected *
  page161_i9
#ISCELL
  pure_quanta_power universal_power *
  page161_i90
#CELL
  pure_quanta q_res *
  page161_i91
#ISCELL
  pure_quanta_power universal_power *
  page161_i92
#CELL
  pure_quanta q_res *
  page161_i93
#ISCELL
  standard offpage *
  page161_i94
#ISCELL
  standard offpage *
  page161_i95
#ISCELL
  standard offpage *
  page161_i96
